# S9S_MB_2U (Grand Teton) — schematic netlist excerpt (pin names and nets, part order shuffled) for the footprints in the layout excerpt that follows; sources: Cadence DE-HDL packaged netlist, KiCad conversion of 03242023_DA0F0TMBIJ0_F0T_Motherboard_J_brd_V01_OCP.brd

R4761  Q_RES  10K 1% CHIP  pkg 0402LF  page 162 : A = P3V3_AUX ; B = HP_LVC3_OCP_V3_2_PRSNT2_PLD_N
PC530_P1_3  Q_CAP  1UF 16V 10% X6S  pkg C0402  page 286 : A = SW_P12V_PVCCIN_CPU1_FLT ; B = GND
C218  Q_CAP  47UF 4V 20% X6S  pkg C0805  page 74 : A = PVCCIN_CPU0 ; B = GND

(kicad_pcb
	(version 20260206)
	(generator "pcbnew")
	(generator_version "10.0")
	(general
		(thickness 1.6)
		(legacy_teardrops no)
	)
	(paper "A4")
	(title_block
		(title "03242023_DA0F0TMBIJ0_F0T_Motherboard_J_brd_V01_OCP.brd")
		(comment 1 "Grand Teton / footprints 1047-1049 of 6105")
	)
	(layers
		(0 "F.Cu" signal "TOP")
		(4 "In1.Cu" signal "GND")
		(6 "In2.Cu" signal "IN1")
		(8 "In3.Cu" signal "GND1")
		(10 "In4.Cu" signal "IN2")
		(12 "In5.Cu" signal "GND2")
		(14 "In6.Cu" signal "IN3")
		(16 "In7.Cu" signal "GND3")
		(18 "In8.Cu" signal "VCC")
		(20 "In9.Cu" signal "VCC1")
		(22 "In10.Cu" signal "GND4")
		(24 "In11.Cu" signal "IN4")
		(26 "In12.Cu" signal "GND5")
		(28 "In13.Cu" signal "IN5")
		(30 "In14.Cu" signal "GND6")
		(32 "In15.Cu" signal "IN6")
		(34 "In16.Cu" signal "GND7")
		(2 "B.Cu" signal "BOTTOM")
		(9 "F.Adhes" user "F.Adhesive")
		(11 "B.Adhes" user "B.Adhesive")
		(13 "F.Paste" user "Package Geometry/Pastemask Top")
		(15 "B.Paste" user "Package Geometry/Pastemask Bottom")
		(5 "F.SilkS" user "Ref Des/Silkscreen Top")
		(7 "B.SilkS" user "Ref Des/Silkscreen Bottom")
		(1 "F.Mask" user "Board Geometry/Soldermask Top")
		(3 "B.Mask" user "Board Geometry/Soldermask Bottom")
		(17 "Dwgs.User" user "User.Drawings")
		(19 "Cmts.User" user "User.Comments")
		(21 "Eco1.User" user "User.Eco1")
		(23 "Eco2.User" user "User.Eco2")
		(25 "Edge.Cuts" user "Board Geometry/Outline")
		(27 "Margin" user)
		(31 "F.CrtYd" user "Package Geometry/Place Bound Top")
		(29 "B.CrtYd" user "Package Geometry/Place Bound Bottom")
		(35 "F.Fab" user "Ref Des/Assembly Top")
		(33 "B.Fab" user "Ref Des/Assembly Bottom")
	)
	(footprint ""
		(layer "F.Cu")
		(at 116.888006 -333.804514 -90)
		(property "Reference" "PC530_P1_3"
			(at 0 0 270)
			(layer "F.SilkS")
			(hide yes)
			(effects
				(font
					(size 1.27 1.27)
				)
			)
		)
		(property "Value" ""
			(at 0 0 270)
			(layer "F.Fab")
			(effects
				(font
					(size 1.27 1.27)
				)
			)
		)
		(duplicate_pad_numbers_are_jumpers no)
		(fp_line
			(start -0.7874 0.4064)
			(end -0.7874 -0.4064)
			(stroke
				(width 0.1524)
				(type default)
			)
			(layer "F.SilkS")
		)
		(fp_line
			(start 0.7874 0.4064)
			(end -0.7874 0.4064)
			(stroke
				(width 0.1524)
				(type default)
			)
			(layer "F.SilkS")
		)
		(fp_line
			(start -0.7874 -0.4064)
			(end 0.7874 -0.4064)
			(stroke
				(width 0.1524)
				(type default)
			)
			(layer "F.SilkS")
		)
		(fp_line
			(start 0.7874 -0.4064)
			(end 0.7874 0.4064)
			(stroke
				(width 0.1524)
				(type default)
			)
			(layer "F.SilkS")
		)
		(fp_line
			(start -0.67945 0.3048)
			(end -0.67945 -0.305054)
			(stroke
				(width 0.1)
				(type default)
			)
			(layer "F.Fab")
		)
		(fp_line
			(start -0.12065 0.3048)
			(end -0.67945 0.3048)
			(stroke
				(width 0.1)
				(type default)
			)
			(layer "F.Fab")
		)
		(fp_line
			(start 0.120396 0.3048)
			(end 0.120396 0.2794)
			(stroke
				(width 0.1)
				(type default)
			)
			(layer "F.Fab")
		)
		(fp_line
			(start 0.67945 0.3048)
			(end 0.120396 0.3048)
			(stroke
				(width 0.1)
				(type default)
			)
			(layer "F.Fab")
		)
		(fp_line
			(start -0.12065 0.2794)
			(end -0.12065 0.3048)
			(stroke
				(width 0.1)
				(type default)
			)
			(layer "F.Fab")
		)
		(fp_line
			(start 0.120396 0.2794)
			(end -0.12065 0.2794)
			(stroke
				(width 0.1)
				(type default)
			)
			(layer "F.Fab")
		)
		(fp_line
			(start -0.12065 -0.2794)
			(end 0.12065 -0.2794)
			(stroke
				(width 0.1)
				(type default)
			)
			(layer "F.Fab")
		)
		(fp_line
			(start 0.12065 -0.2794)
			(end 0.12065 -0.3048)
			(stroke
				(width 0.1)
				(type default)
			)
			(layer "F.Fab")
		)
		(fp_line
			(start 0.12065 -0.3048)
			(end 0.67945 -0.3048)
			(stroke
				(width 0.1)
				(type default)
			)
			(layer "F.Fab")
		)
		(fp_line
			(start 0.67945 -0.3048)
			(end 0.67945 0.3048)
			(stroke
				(width 0.1)
				(type default)
			)
			(layer "F.Fab")
		)
		(fp_line
			(start -0.67945 -0.305054)
			(end -0.12065 -0.305054)
			(stroke
				(width 0.1)
				(type default)
			)
			(layer "F.Fab")
		)
		(fp_line
			(start -0.12065 -0.305054)
			(end -0.12065 -0.2794)
			(stroke
				(width 0.1)
				(type default)
			)
			(layer "F.Fab")
		)
		(pad "1" smd circle
			(at -0.40005 0 270)
			(size 0 0)
			(layers "F.Cu" "F.Mask" "F.Paste")
			(net "SW_P12V_PVCCIN_CPU1_FLT")
		)
		(pad "2" smd circle
			(at 0.40005 0 270)
			(size 0 0)
			(layers "F.Cu" "F.Mask" "F.Paste")
			(net "GND")
		)
	)
	(footprint ""
		(layer "F.Cu")
		(at 359.71988 -296.05478 180)
		(property "Reference" "C218"
			(at 0 0 180)
			(layer "F.SilkS")
			(hide yes)
			(effects
				(font
					(size 1.27 1.27)
				)
			)
		)
		(property "Value" ""
			(at 0 0 180)
			(layer "F.Fab")
			(effects
				(font
					(size 1.27 1.27)
				)
			)
		)
		(duplicate_pad_numbers_are_jumpers no)
		(fp_line
			(start 1.524 0.762)
			(end -1.524 0.762)
			(stroke
				(width 0.1524)
				(type default)
			)
			(layer "F.SilkS")
		)
		(fp_line
			(start 1.524 -0.762)
			(end 1.524 0.762)
			(stroke
				(width 0.1524)
				(type default)
			)
			(layer "F.SilkS")
		)
		(fp_line
			(start -1.524 0.762)
			(end -1.524 -0.762)
			(stroke
				(width 0.1524)
				(type default)
			)
			(layer "F.SilkS")
		)
		(fp_line
			(start -1.524 -0.762)
			(end 1.524 -0.762)
			(stroke
				(width 0.1524)
				(type default)
			)
			(layer "F.SilkS")
		)
		(fp_line
			(start 1.1049 0.724916)
			(end 1.1049 -0.724916)
			(stroke
				(width 0.1)
				(type default)
			)
			(layer "F.Fab")
		)
		(fp_line
			(start 1.1049 -0.724916)
			(end -1.1049 -0.724916)
			(stroke
				(width 0.1)
				(type default)
			)
			(layer "F.Fab")
		)
		(fp_line
			(start -1.1049 0.724916)
			(end 1.1049 0.724916)
			(stroke
				(width 0.1)
				(type default)
			)
			(layer "F.Fab")
		)
		(fp_line
			(start -1.1049 -0.724916)
			(end -1.1049 0.724916)
			(stroke
				(width 0.1)
				(type default)
			)
			(layer "F.Fab")
		)
		(pad "1" smd rect
			(at -0.889 0)
			(size 1.016 1.27)
			(layers "F.Cu" "F.Mask" "F.Paste")
			(net "PVCCIN_CPU0")
		)
		(pad "2" smd rect
			(at 0.889 0)
			(size 1.016 1.27)
			(layers "F.Cu" "F.Mask" "F.Paste")
			(net "GND")
		)
	)
	(footprint ""
		(layer "F.Cu")
		(at 31.8516 -69.7992 180)
		(property "Reference" "R4761"
			(at 0 0 180)
			(layer "F.SilkS")
			(hide yes)
			(effects
				(font
					(size 1.27 1.27)
				)
			)
		)
		(property "Value" ""
			(at 0 0 180)
			(layer "F.Fab")
			(effects
				(font
					(size 1.27 1.27)
				)
			)
		)
		(duplicate_pad_numbers_are_jumpers no)
		(fp_line
			(start 0.7874 0.4064)
			(end -0.7874 0.4064)
			(stroke
				(width 0.1524)
				(type default)
			)
			(layer "F.SilkS")
		)
		(fp_line
			(start 0.7874 -0.4064)
			(end 0.7874 0.4064)
			(stroke
				(width 0.1524)
				(type default)
			)
			(layer "F.SilkS")
		)
		(fp_line
			(start -0.7874 0.4064)
			(end -0.7874 -0.4064)
			(stroke
				(width 0.1524)
				(type default)
			)
			(layer "F.SilkS")
		)
		(fp_line
			(start -0.7874 -0.4064)
			(end 0.7874 -0.4064)
			(stroke
				(width 0.1524)
				(type default)
			)
			(layer "F.SilkS")
		)
		(fp_line
			(start 0.67945 0.3048)
			(end 0.120396 0.3048)
			(stroke
				(width 0.1)
				(type default)
			)
			(layer "F.Fab")
		)
		(fp_line
			(start 0.67945 -0.3048)
			(end 0.67945 0.3048)
			(stroke
				(width 0.1)
				(type default)
			)
			(layer "F.Fab")
		)
		(fp_line
			(start 0.12065 -0.2794)
			(end 0.12065 -0.3048)
			(stroke
				(width 0.1)
				(type default)
			)
			(layer "F.Fab")
		)
		(fp_line
			(start 0.12065 -0.3048)
			(end 0.67945 -0.3048)
			(stroke
				(width 0.1)
				(type default)
			)
			(layer "F.Fab")
		)
		(fp_line
			(start 0.120396 0.3048)
			(end 0.120396 0.2794)
			(stroke
				(width 0.1)
				(type default)
			)
			(layer "F.Fab")
		)
		(fp_line
			(start 0.120396 0.2794)
			(end -0.12065 0.2794)
			(stroke
				(width 0.1)
				(type default)
			)
			(layer "F.Fab")
		)
		(fp_line
			(start -0.12065 0.3048)
			(end -0.67945 0.3048)
			(stroke
				(width 0.1)
				(type default)
			)
			(layer "F.Fab")
		)
		(fp_line
			(start -0.12065 0.2794)
			(end -0.12065 0.3048)
			(stroke
				(width 0.1)
				(type default)
			)
			(layer "F.Fab")
		)
		(fp_line
			(start -0.12065 -0.2794)
			(end 0.12065 -0.2794)
			(stroke
				(width 0.1)
				(type default)
			)
			(layer "F.Fab")
		)
		(fp_line
			(start -0.12065 -0.305054)
			(end -0.12065 -0.2794)
			(stroke
				(width 0.1)
				(type default)
			)
			(layer "F.Fab")
		)
		(fp_line
			(start -0.67945 0.3048)
			(end -0.67945 -0.305054)
			(stroke
				(width 0.1)
				(type default)
			)
			(layer "F.Fab")
		)
		(fp_line
			(start -0.67945 -0.305054)
			(end -0.12065 -0.305054)
			(stroke
				(width 0.1)
				(type default)
			)
			(layer "F.Fab")
		)
		(pad "1" smd circle
			(at -0.40005 0 180)
			(size 0 0)
			(layers "F.Cu" "F.Mask" "F.Paste")
			(net "P3V3_AUX")
		)
		(pad "2" smd circle
			(at 0.40005 0 180)
			(size 0 0)
			(layers "F.Cu" "F.Mask" "F.Paste")
			(net "HP_LVC3_OCP_V3_2_PRSNT2_PLD_N")
		)
	)
)
